# T6G (Grand Teton) — schematic netlist excerpt (pin names and nets, part order shuffled) for the footprints in the layout excerpt that follows; sources: Cadence DE-HDL packaged netlist, KiCad conversion of 04192023_DAF0TMB3IC0_F0TG_MB_C_brd_V02_OCP.brd

PC599  Q_CAP  0.1UF 25V 10% X7R  pkg 0402  page 198 : A = PVDDCR_SOC_P0 ; B = GND

U253  74LVC2G17GW  IC  pkg SOT363  page 128
  A0  = GPU_FPGA_BOOT_EN
  GND  = GND
  A1  = GPU_BASE_STBY_EN
  B1  = GPU_BASE_STBY_EN_BUF_R
  VCC  = P3V3_AUX
  B0  = GPU_FPGA_BOOT_EN_BUF_R

(kicad_pcb
	(version 20260206)
	(generator "pcbnew")
	(generator_version "10.0")
	(general
		(thickness 1.6)
		(legacy_teardrops no)
	)
	(paper "A4")
	(title_block
		(title "04192023_DAF0TMB3IC0_F0TG_MB_C_brd_V02_OCP.brd")
		(comment 1 "Grand Teton / footprints 3390-3391 of 8354")
	)
	(layers
		(0 "F.Cu" signal "TOP")
		(4 "In1.Cu" signal "GND")
		(6 "In2.Cu" signal "IN1")
		(8 "In3.Cu" signal "GND1")
		(10 "In4.Cu" signal "IN2")
		(12 "In5.Cu" signal "GND2")
		(14 "In6.Cu" signal "IN3")
		(16 "In7.Cu" signal "GND3")
		(18 "In8.Cu" signal "VCC")
		(20 "In9.Cu" signal "VCC1")
		(22 "In10.Cu" signal "GND4")
		(24 "In11.Cu" signal "IN4")
		(26 "In12.Cu" signal "GND5")
		(28 "In13.Cu" signal "IN5")
		(30 "In14.Cu" signal "GND6")
		(32 "In15.Cu" signal "IN6")
		(34 "In16.Cu" signal "GND7")
		(2 "B.Cu" signal "BOTTOM")
		(9 "F.Adhes" user "F.Adhesive")
		(11 "B.Adhes" user "B.Adhesive")
		(13 "F.Paste" user "Package Geometry/Pastemask Top")
		(15 "B.Paste" user "Package Geometry/Pastemask Bottom")
		(5 "F.SilkS" user "Ref Des/Silkscreen Top")
		(7 "B.SilkS" user "Ref Des/Silkscreen Bottom")
		(1 "F.Mask" user "Board Geometry/Soldermask Top")
		(3 "B.Mask" user "Board Geometry/Soldermask Bottom")
		(17 "Dwgs.User" user "User.Drawings")
		(19 "Cmts.User" user "User.Comments")
		(21 "Eco1.User" user "User.Eco1")
		(23 "Eco2.User" user "User.Eco2")
		(25 "Edge.Cuts" user "Board Geometry/Outline")
		(27 "Margin" user)
		(31 "F.CrtYd" user "Package Geometry/Place Bound Top")
		(29 "B.CrtYd" user "Package Geometry/Place Bound Bottom")
		(35 "F.Fab" user "Ref Des/Assembly Top")
		(33 "B.Fab" user "Ref Des/Assembly Bottom")
	)
	(footprint ""
		(layer "F.Cu")
		(at 419.597586 -176.338738 -90)
		(property "Reference" "PC599"
			(at 0 0 270)
			(layer "F.SilkS")
			(hide yes)
			(effects
				(font
					(size 1.27 1.27)
				)
			)
		)
		(property "Value" ""
			(at 0 0 270)
			(layer "F.Fab")
			(effects
				(font
					(size 1.27 1.27)
				)
			)
		)
		(duplicate_pad_numbers_are_jumpers no)
		(fp_line
			(start -0.7874 0.4064)
			(end -0.7874 -0.4064)
			(stroke
				(width 0.1524)
				(type default)
			)
			(layer "F.SilkS")
		)
		(fp_line
			(start 0.7874 0.4064)
			(end -0.7874 0.4064)
			(stroke
				(width 0.1524)
				(type default)
			)
			(layer "F.SilkS")
		)
		(fp_line
			(start -0.7874 -0.4064)
			(end 0.7874 -0.4064)
			(stroke
				(width 0.1524)
				(type default)
			)
			(layer "F.SilkS")
		)
		(fp_line
			(start 0.7874 -0.4064)
			(end 0.7874 0.4064)
			(stroke
				(width 0.1524)
				(type default)
			)
			(layer "F.SilkS")
		)
		(fp_line
			(start -0.67945 0.3048)
			(end -0.67945 -0.305054)
			(stroke
				(width 0.1)
				(type default)
			)
			(layer "F.Fab")
		)
		(fp_line
			(start -0.12065 0.3048)
			(end -0.67945 0.3048)
			(stroke
				(width 0.1)
				(type default)
			)
			(layer "F.Fab")
		)
		(fp_line
			(start 0.120396 0.3048)
			(end 0.120396 0.2794)
			(stroke
				(width 0.1)
				(type default)
			)
			(layer "F.Fab")
		)
		(fp_line
			(start 0.67945 0.3048)
			(end 0.120396 0.3048)
			(stroke
				(width 0.1)
				(type default)
			)
			(layer "F.Fab")
		)
		(fp_line
			(start -0.12065 0.2794)
			(end -0.12065 0.3048)
			(stroke
				(width 0.1)
				(type default)
			)
			(layer "F.Fab")
		)
		(fp_line
			(start 0.120396 0.2794)
			(end -0.12065 0.2794)
			(stroke
				(width 0.1)
				(type default)
			)
			(layer "F.Fab")
		)
		(fp_line
			(start -0.12065 -0.2794)
			(end 0.12065 -0.2794)
			(stroke
				(width 0.1)
				(type default)
			)
			(layer "F.Fab")
		)
		(fp_line
			(start 0.12065 -0.2794)
			(end 0.12065 -0.3048)
			(stroke
				(width 0.1)
				(type default)
			)
			(layer "F.Fab")
		)
		(fp_line
			(start 0.12065 -0.3048)
			(end 0.67945 -0.3048)
			(stroke
				(width 0.1)
				(type default)
			)
			(layer "F.Fab")
		)
		(fp_line
			(start 0.67945 -0.3048)
			(end 0.67945 0.3048)
			(stroke
				(width 0.1)
				(type default)
			)
			(layer "F.Fab")
		)
		(fp_line
			(start -0.67945 -0.305054)
			(end -0.12065 -0.305054)
			(stroke
				(width 0.1)
				(type default)
			)
			(layer "F.Fab")
		)
		(fp_line
			(start -0.12065 -0.305054)
			(end -0.12065 -0.2794)
			(stroke
				(width 0.1)
				(type default)
			)
			(layer "F.Fab")
		)
		(pad "1" smd circle
			(at -0.40005 0 270)
			(size 0 0)
			(layers "F.Cu" "F.Mask" "F.Paste")
			(net "PVDDCR_SOC_P0")
		)
		(pad "2" smd circle
			(at 0.40005 0 270)
			(size 0 0)
			(layers "F.Cu" "F.Mask" "F.Paste")
			(net "GND")
		)
	)
	(footprint ""
		(layer "F.Cu")
		(at 119.458486 -428.873412 -90)
		(property "Reference" "U253"
			(at 1.385824 1.781302 90)
			(unlocked yes)
			(layer "F.SilkS")
			(effects
				(font
					(size 0.7874 0.5842)
					(thickness 0.1524)
				)
				(justify left)
			)
		)
		(property "Value" ""
			(at 0 0 270)
			(layer "F.Fab")
			(effects
				(font
					(size 1.27 1.27)
				)
			)
		)
		(duplicate_pad_numbers_are_jumpers no)
		(fp_line
			(start -1.3462 1.100074)
			(end -1.3462 -1.100074)
			(stroke
				(width 0.1524)
				(type default)
			)
			(layer "F.SilkS")
		)
		(fp_line
			(start 1.3462 1.100074)
			(end -1.3462 1.100074)
			(stroke
				(width 0.1524)
				(type default)
			)
			(layer "F.SilkS")
		)
		(fp_line
			(start 0 -0.381)
			(end 0.670052 -1.100074)
			(stroke
				(width 0.1524)
				(type default)
			)
			(layer "F.SilkS")
		)
		(fp_line
			(start -1.3462 -1.100074)
			(end -0.670052 -1.100074)
			(stroke
				(width 0.1524)
				(type default)
			)
			(layer "F.SilkS")
		)
		(fp_line
			(start -0.670052 -1.100074)
			(end 0 -0.381)
			(stroke
				(width 0.1524)
				(type default)
			)
			(layer "F.SilkS")
		)
		(fp_line
			(start 0.670052 -1.100074)
			(end 1.3462 -1.100074)
			(stroke
				(width 0.1524)
				(type default)
			)
			(layer "F.SilkS")
		)
		(fp_line
			(start 1.3462 -1.100074)
			(end 1.3462 1.100074)
			(stroke
				(width 0.1524)
				(type default)
			)
			(layer "F.SilkS")
		)
		(fp_poly
			(pts
				(xy -1.616456 -1.671066) (xy -1.001522 -1.930146) (xy -1.049782 -1.185164)
			)
			(stroke
				(width 0)
				(type default)
			)
			(fill yes)
			(layer "F.SilkS")
		)
		(fp_line
			(start -0.670052 1.100074)
			(end -0.670052 0.8001)
			(stroke
				(width 0.1)
				(type default)
			)
			(layer "F.Fab")
		)
		(fp_line
			(start 0.670052 1.100074)
			(end -0.670052 1.100074)
			(stroke
				(width 0.1)
				(type default)
			)
			(layer "F.Fab")
		)
		(fp_line
			(start -1.100074 0.8001)
			(end -1.100074 -0.8001)
			(stroke
				(width 0.1)
				(type default)
			)
			(layer "F.Fab")
		)
		(fp_line
			(start -0.670052 0.8001)
			(end -1.100074 0.8001)
			(stroke
				(width 0.1)
				(type default)
			)
			(layer "F.Fab")
		)
		(fp_line
			(start -0.670052 0.8001)
			(end -0.670052 -0.8001)
			(stroke
				(width 0.1)
				(type default)
			)
			(layer "F.Fab")
		)
		(fp_line
			(start 0.670052 0.8001)
			(end 0.670052 1.100074)
			(stroke
				(width 0.1)
				(type default)
			)
			(layer "F.Fab")
		)
		(fp_line
			(start 1.100074 0.8001)
			(end 0.670052 0.8001)
			(stroke
				(width 0.1)
				(type default)
			)
			(layer "F.Fab")
		)
		(fp_line
			(start -1.100074 -0.8001)
			(end -0.670052 -0.8001)
			(stroke
				(width 0.1)
				(type default)
			)
			(layer "F.Fab")
		)
		(fp_line
			(start -0.670052 -0.8001)
			(end -0.670052 -1.100074)
			(stroke
				(width 0.1)
				(type default)
			)
			(layer "F.Fab")
		)
		(fp_line
			(start 0.670052 -0.8001)
			(end 0.670052 0.8001)
			(stroke
				(width 0.1)
				(type default)
			)
			(layer "F.Fab")
		)
		(fp_line
			(start 0.670052 -0.8001)
			(end 1.100074 -0.8001)
			(stroke
				(width 0.1)
				(type default)
			)
			(layer "F.Fab")
		)
		(fp_line
			(start 1.100074 -0.8001)
			(end 1.100074 0.8001)
			(stroke
				(width 0.1)
				(type default)
			)
			(layer "F.Fab")
		)
		(fp_line
			(start -0.670052 -1.100074)
			(end 0.670052 -1.100074)
			(stroke
				(width 0.1)
				(type default)
			)
			(layer "F.Fab")
		)
		(fp_line
			(start 0.670052 -1.100074)
			(end 0.670052 -0.8001)
			(stroke
				(width 0.1)
				(type default)
			)
			(layer "F.Fab")
		)
		(fp_poly
			(pts
				(xy -1.524 -0.649986) (xy -2.286 -1.030986) (xy -2.286 -0.268986)
			)
			(stroke
				(width 0)
				(type default)
			)
			(fill yes)
			(layer "F.Fab")
		)
		(pad "1" smd rect
			(at -0.94996 -0.649986 180)
			(size 0.4064 0.508)
			(layers "F.Cu" "F.Mask" "F.Paste")
			(net "GPU_FPGA_BOOT_EN")
		)
		(pad "2" smd rect
			(at -0.94996 0 180)
			(size 0.4064 0.508)
			(layers "F.Cu" "F.Mask" "F.Paste")
			(net "GND")
		)
		(pad "3" smd rect
			(at -0.94996 0.649986 180)
			(size 0.4064 0.508)
			(layers "F.Cu" "F.Mask" "F.Paste")
			(net "GPU_BASE_STBY_EN")
		)
		(pad "4" smd rect
			(at 0.94996 0.649986 180)
			(size 0.4064 0.508)
			(layers "F.Cu" "F.Mask" "F.Paste")
			(net "GPU_BASE_STBY_EN_BUF_R")
		)
		(pad "5" smd rect
			(at 0.94996 0 180)
			(size 0.4064 0.508)
			(layers "F.Cu" "F.Mask" "F.Paste")
			(net "P3V3_AUX")
		)
		(pad "6" smd rect
			(at 0.94996 -0.649986 180)
			(size 0.4064 0.508)
			(layers "F.Cu" "F.Mask" "F.Paste")
			(net "GPU_FPGA_BOOT_EN_BUF_R")
		)
	)
)
